# T6G (Grand Teton) — schematic netlist excerpt (pin names and nets, part order shuffled) for the footprints in the layout excerpt that follows; sources: Cadence DE-HDL packaged netlist, KiCad conversion of 04192023_DAF0TMB3IC0_F0TG_MB_C_brd_V02_OCP.brd

C4178  Q_CAP  22UF 4V 20% X6S  pkg C0402  page 69 : A = PVDDCR_CPU0_P0 ; B = GND
C2482  Q_CAP  22UF 4V 20% X6S  pkg C0402  page 74 : A = PVDD11_S3_P1 ; B = GND

(kicad_pcb
	(version 20260206)
	(generator "pcbnew")
	(generator_version "10.0")
	(general
		(thickness 1.6)
		(legacy_teardrops no)
	)
	(paper "A4")
	(title_block
		(title "04192023_DAF0TMB3IC0_F0TG_MB_C_brd_V02_OCP.brd")
		(comment 1 "Grand Teton / footprints 7805-7806 of 8354")
	)
	(layers
		(0 "F.Cu" signal "TOP")
		(4 "In1.Cu" signal "GND")
		(6 "In2.Cu" signal "IN1")
		(8 "In3.Cu" signal "GND1")
		(10 "In4.Cu" signal "IN2")
		(12 "In5.Cu" signal "GND2")
		(14 "In6.Cu" signal "IN3")
		(16 "In7.Cu" signal "GND3")
		(18 "In8.Cu" signal "VCC")
		(20 "In9.Cu" signal "VCC1")
		(22 "In10.Cu" signal "GND4")
		(24 "In11.Cu" signal "IN4")
		(26 "In12.Cu" signal "GND5")
		(28 "In13.Cu" signal "IN5")
		(30 "In14.Cu" signal "GND6")
		(32 "In15.Cu" signal "IN6")
		(34 "In16.Cu" signal "GND7")
		(2 "B.Cu" signal "BOTTOM")
		(9 "F.Adhes" user "F.Adhesive")
		(11 "B.Adhes" user "B.Adhesive")
		(13 "F.Paste" user "Package Geometry/Pastemask Top")
		(15 "B.Paste" user "Package Geometry/Pastemask Bottom")
		(5 "F.SilkS" user "Ref Des/Silkscreen Top")
		(7 "B.SilkS" user "Ref Des/Silkscreen Bottom")
		(1 "F.Mask" user "Board Geometry/Soldermask Top")
		(3 "B.Mask" user "Board Geometry/Soldermask Bottom")
		(17 "Dwgs.User" user "User.Drawings")
		(19 "Cmts.User" user "User.Comments")
		(21 "Eco1.User" user "User.Eco1")
		(23 "Eco2.User" user "User.Eco2")
		(25 "Edge.Cuts" user "Board Geometry/Outline")
		(27 "Margin" user)
		(31 "F.CrtYd" user "Package Geometry/Place Bound Top")
		(29 "B.CrtYd" user "Package Geometry/Place Bound Bottom")
		(35 "F.Fab" user "Ref Des/Assembly Top")
		(33 "B.Fab" user "Ref Des/Assembly Bottom")
	)
	(footprint ""
		(layer "B.Cu")
		(at 121.944638 -263.465564)
		(property "Reference" "C2482"
			(at 0 0 0)
			(layer "B.SilkS")
			(hide yes)
			(effects
				(font
					(size 1.27 1.27)
				)
				(justify mirror)
			)
		)
		(property "Value" ""
			(at 0 0 0)
			(layer "B.Fab")
			(effects
				(font
					(size 1.27 1.27)
				)
				(justify mirror)
			)
		)
		(duplicate_pad_numbers_are_jumpers no)
		(fp_line
			(start -0.7874 -0.4064)
			(end -0.7874 0.4064)
			(stroke
				(width 0.1524)
				(type default)
			)
			(layer "B.SilkS")
		)
		(fp_line
			(start -0.7874 0.4064)
			(end 0.7874 0.4064)
			(stroke
				(width 0.1524)
				(type default)
			)
			(layer "B.SilkS")
		)
		(fp_line
			(start 0.7874 -0.4064)
			(end -0.7874 -0.4064)
			(stroke
				(width 0.1524)
				(type default)
			)
			(layer "B.SilkS")
		)
		(fp_line
			(start 0.7874 0.4064)
			(end 0.7874 -0.4064)
			(stroke
				(width 0.1524)
				(type default)
			)
			(layer "B.SilkS")
		)
		(fp_line
			(start -0.67945 -0.3048)
			(end -0.67945 0.3048)
			(stroke
				(width 0.1)
				(type default)
			)
			(layer "B.Fab")
		)
		(fp_line
			(start -0.67945 0.3048)
			(end -0.120396 0.3048)
			(stroke
				(width 0.1)
				(type default)
			)
			(layer "B.Fab")
		)
		(fp_line
			(start -0.12065 -0.3048)
			(end -0.67945 -0.3048)
			(stroke
				(width 0.1)
				(type default)
			)
			(layer "B.Fab")
		)
		(fp_line
			(start -0.12065 -0.2794)
			(end -0.12065 -0.3048)
			(stroke
				(width 0.1)
				(type default)
			)
			(layer "B.Fab")
		)
		(fp_line
			(start -0.120396 0.2794)
			(end 0.12065 0.2794)
			(stroke
				(width 0.1)
				(type default)
			)
			(layer "B.Fab")
		)
		(fp_line
			(start -0.120396 0.3048)
			(end -0.120396 0.2794)
			(stroke
				(width 0.1)
				(type default)
			)
			(layer "B.Fab")
		)
		(fp_line
			(start 0.12065 -0.305054)
			(end 0.12065 -0.2794)
			(stroke
				(width 0.1)
				(type default)
			)
			(layer "B.Fab")
		)
		(fp_line
			(start 0.12065 -0.2794)
			(end -0.12065 -0.2794)
			(stroke
				(width 0.1)
				(type default)
			)
			(layer "B.Fab")
		)
		(fp_line
			(start 0.12065 0.2794)
			(end 0.12065 0.3048)
			(stroke
				(width 0.1)
				(type default)
			)
			(layer "B.Fab")
		)
		(fp_line
			(start 0.12065 0.3048)
			(end 0.67945 0.3048)
			(stroke
				(width 0.1)
				(type default)
			)
			(layer "B.Fab")
		)
		(fp_line
			(start 0.67945 -0.305054)
			(end 0.12065 -0.305054)
			(stroke
				(width 0.1)
				(type default)
			)
			(layer "B.Fab")
		)
		(fp_line
			(start 0.67945 0.3048)
			(end 0.67945 -0.305054)
			(stroke
				(width 0.1)
				(type default)
			)
			(layer "B.Fab")
		)
		(pad "1" smd circle
			(at 0.40005 0 180)
			(size 0 0)
			(layers "B.Cu" "B.Mask" "B.Paste")
			(net "PVDD11_S3_P1")
		)
		(pad "2" smd circle
			(at -0.40005 0 180)
			(size 0 0)
			(layers "B.Cu" "B.Mask" "B.Paste")
			(net "GND")
		)
	)
	(footprint ""
		(layer "B.Cu")
		(at 349.320358 -248.47931 180)
		(property "Reference" "C4178"
			(at 0 0 0)
			(layer "B.SilkS")
			(hide yes)
			(effects
				(font
					(size 1.27 1.27)
				)
				(justify mirror)
			)
		)
		(property "Value" ""
			(at 0 0 0)
			(layer "B.Fab")
			(effects
				(font
					(size 1.27 1.27)
				)
				(justify mirror)
			)
		)
		(duplicate_pad_numbers_are_jumpers no)
		(fp_line
			(start 0.7874 0.4064)
			(end 0.7874 -0.4064)
			(stroke
				(width 0.1524)
				(type default)
			)
			(layer "B.SilkS")
		)
		(fp_line
			(start 0.7874 -0.4064)
			(end -0.7874 -0.4064)
			(stroke
				(width 0.1524)
				(type default)
			)
			(layer "B.SilkS")
		)
		(fp_line
			(start -0.7874 0.4064)
			(end 0.7874 0.4064)
			(stroke
				(width 0.1524)
				(type default)
			)
			(layer "B.SilkS")
		)
		(fp_line
			(start -0.7874 -0.4064)
			(end -0.7874 0.4064)
			(stroke
				(width 0.1524)
				(type default)
			)
			(layer "B.SilkS")
		)
		(fp_line
			(start 0.67945 0.3048)
			(end 0.67945 -0.305054)
			(stroke
				(width 0.1)
				(type default)
			)
			(layer "B.Fab")
		)
		(fp_line
			(start 0.67945 -0.305054)
			(end 0.12065 -0.305054)
			(stroke
				(width 0.1)
				(type default)
			)
			(layer "B.Fab")
		)
		(fp_line
			(start 0.12065 0.3048)
			(end 0.67945 0.3048)
			(stroke
				(width 0.1)
				(type default)
			)
			(layer "B.Fab")
		)
		(fp_line
			(start 0.12065 0.2794)
			(end 0.12065 0.3048)
			(stroke
				(width 0.1)
				(type default)
			)
			(layer "B.Fab")
		)
		(fp_line
			(start 0.12065 -0.2794)
			(end -0.12065 -0.2794)
			(stroke
				(width 0.1)
				(type default)
			)
			(layer "B.Fab")
		)
		(fp_line
			(start 0.12065 -0.305054)
			(end 0.12065 -0.2794)
			(stroke
				(width 0.1)
				(type default)
			)
			(layer "B.Fab")
		)
		(fp_line
			(start -0.120396 0.3048)
			(end -0.120396 0.2794)
			(stroke
				(width 0.1)
				(type default)
			)
			(layer "B.Fab")
		)
		(fp_line
			(start -0.120396 0.2794)
			(end 0.12065 0.2794)
			(stroke
				(width 0.1)
				(type default)
			)
			(layer "B.Fab")
		)
		(fp_line
			(start -0.12065 -0.2794)
			(end -0.12065 -0.3048)
			(stroke
				(width 0.1)
				(type default)
			)
			(layer "B.Fab")
		)
		(fp_line
			(start -0.12065 -0.3048)
			(end -0.67945 -0.3048)
			(stroke
				(width 0.1)
				(type default)
			)
			(layer "B.Fab")
		)
		(fp_line
			(start -0.67945 0.3048)
			(end -0.120396 0.3048)
			(stroke
				(width 0.1)
				(type default)
			)
			(layer "B.Fab")
		)
		(fp_line
			(start -0.67945 -0.3048)
			(end -0.67945 0.3048)
			(stroke
				(width 0.1)
				(type default)
			)
			(layer "B.Fab")
		)
		(pad "1" smd circle
			(at 0.40005 0)
			(size 0 0)
			(layers "B.Cu" "B.Mask" "B.Paste")
			(net "PVDDCR_CPU0_P0")
		)
		(pad "2" smd circle
			(at -0.40005 0)
			(size 0 0)
			(layers "B.Cu" "B.Mask" "B.Paste")
			(net "GND")
		)
	)
)
